# BASEBOARD_FAB2 (Tioga Pass) — schematic parts with pin connectivity, parts 2359–2359 of 4751; source: Cadence DE-HDL packaged netlist (pstxprt.dat, pstxnet.dat, pstchip.dat)

J1G2  SCONN288_H44441004  SCONN  pkg PIP  page 79
  1  \12v\(1)  = P12V_NVDIMM_GHJ
  2  VSS(93)  GROUND  = GND
  3  DQ(4)  BI  = M_H_DQ<5>
  4  VSS(92)  GROUND  = GND
  5  DQ(0)  BI  = M_H_DQ<1>
  6  VSS(91)  GROUND  = GND
  7  DQS9P  BI  = M_H_DQS_DP<9>
  8  DQS9N  BI  = M_H_DQS_DN<9>
  9  VSS(90)  GROUND  = GND
  10  DQ(6)  BI  = M_H_DQ<7>
  11  VSS(89)  GROUND  = GND
  12  DQ(2)  BI  = M_H_DQ<3>
  13  VSS(88)  GROUND  = GND
  14  DQ(12)  BI  = M_H_DQ<13>
  15  VSS(87)  GROUND  = GND
  16  DQ(8)  BI  = M_H_DQ<9>
  17  VSS(86)  GROUND  = GND
  18  DQS10P  BI  = M_H_DQS_DP<10>
  19  DQS10N  BI  = M_H_DQS_DN<10>
  20  VSS(85)  GROUND  = GND
  21  DQ(14)  BI  = M_H_DQ<15>
  22  VSS(84)  GROUND  = GND
  23  DQ(10)  BI  = M_H_DQ<11>
  24  VSS(83)  GROUND  = GND
  25  DQ(20)  BI  = M_H_DQ<21>
  26  VSS(82)  GROUND  = GND
  27  DQ(16)  BI  = M_H_DQ<17>
  28  VSS(81)  GROUND  = GND
  29  DQS11P  BI  = M_H_DQS_DP<11>
  30  DQS11N  BI  = M_H_DQS_DN<11>
  31  VSS(80)  GROUND  = GND
  32  DQ(22)  BI  = M_H_DQ<23>
  33  VSS(79)  GROUND  = GND
  34  DQ(18)  BI  = M_H_DQ<19>
  35  VSS(78)  GROUND  = GND
  36  DQ(28)  BI  = M_H_DQ<29>
  37  VSS(77)  GROUND  = GND
  38  DQ(24)  BI  = M_H_DQ<25>
  39  VSS(76)  GROUND  = GND
  40  DQS12P  BI  = M_H_DQS_DP<12>
  41  DQS12N  BI  = M_H_DQS_DN<12>
  42  VSS(75)  GROUND  = GND
  43  DQ(30)  BI  = M_H_DQ<31>
  44  VSS(74)  GROUND  = GND
  45  DQ(26)  BI  = M_H_DQ<27>
  46  VSS(73)  GROUND  = GND
  47  CB(4)  BI  = M_H_ECC<5>
  48  VSS(72)  GROUND  = GND
  49  CB(0)  BI  = M_H_ECC<1>
  50  VSS(71)  GROUND  = GND
  51  DQS17P  BI  = M_H_DQS_DP<17>
  52  DQS17N  BI  = M_H_DQS_DN<17>
  53  VSS(70)  GROUND  = GND
  54  CB(6)  BI  = M_H_ECC<7>
  55  VSS(69)  GROUND  = GND
  56  CB(2)  BI  = M_H_ECC<3>
  57  VSS(68)  GROUND  = GND
  58  RESET_N  BI  = M_GHJ_RST_N
  59  VDD(25)  POWER  = PVDDQ_GHJ
  60  CKE(0)  BI  = M_H_CKE<0>
  61  VDD(24)  POWER  = PVDDQ_GHJ
  62  ACT_N  BI  = M_H_ACT_N
  63  BG(0)  BI  = M_H_BG<0>
  64  VDD(23)  POWER  = PVDDQ_GHJ
  65  A12  BI  = M_H_MA<12>
  66  A9  BI  = M_H_MA<9>
  67  VDD(22)  POWER  = PVDDQ_GHJ
  68  A8  BI  = M_H_MA<8>
  69  A6  BI  = M_H_MA<6>
  70  VDD(21)  POWER  = PVDDQ_GHJ
  71  A3  BI  = M_H_MA<3>
  72  A1  BI  = M_H_MA<1>
  73  VDD(20)  POWER  = PVDDQ_GHJ
  74  CK0P  BI  = M_H_CLK_DP<0>
  75  CK0N  BI  = M_H_CLK_DN<0>
  76  VDD(19)  POWER  = PVDDQ_GHJ
  77  VTT(1)  POWER  = PVTT_GHJ
  78  EVENT_N  BI  = FM_DIMM_EVENT_COD_N
  79  A0  BI  = M_H_MA<0>
  80  VDD(18)  POWER  = PVDDQ_GHJ
  81  BA(0)  BI  = M_H_BA<0>
  82  A16_RAS_N  BI  = M_H_MA<16>
  83  VDD(17)  POWER  = PVDDQ_GHJ
  84  S0_N  BI  = M_H_CS_N<0>
  85  VDD(16)  POWER  = PVDDQ_GHJ
  86  A15_CAS_N  BI  = M_H_MA<15>
  87  ODT(0)  BI  = M_H_ODT<0>
  88  VDD(15)  POWER  = PVDDQ_GHJ
  89  S1_N  BI  = M_H_CS_N<1>
  90  VDD(14)  POWER  = PVDDQ_GHJ
  91  ODT(1)  BI  = M_H_ODT<1>
  92  VDD(13)  POWER  = PVDDQ_GHJ
  93  S2_N_C(0)  BI  = M_H_CS_N<2>
  94  VSS(67)  GROUND  = GND
  95  DQ(36)  BI  = M_H_DQ<37>
  96  VSS(66)  GROUND  = GND
  97  DQ(32)  BI  = M_H_DQ<33>
  98  VSS(65)  GROUND  = GND
  99  DQS13P  BI  = M_H_DQS_DP<13>
  100  DQS13N  BI  = M_H_DQS_DN<13>
  101  VSS(64)  GROUND  = GND
  102  DQ(38)  BI  = M_H_DQ<39>
  103  VSS(63)  GROUND  = GND
  104  DQ(34)  BI  = M_H_DQ<35>
  105  VSS(62)  GROUND  = GND
  106  DQ(44)  BI  = M_H_DQ<45>
  107  VSS(61)  GROUND  = GND
  108  DQ(40)  BI  = M_H_DQ<41>
  109  VSS(60)  GROUND  = GND
  110  DQS14P  BI  = M_H_DQS_DP<14>
  111  DQS14N  BI  = M_H_DQS_DN<14>
  112  VSS(59)  GROUND  = GND
  113  DQ(46)  BI  = M_H_DQ<47>
  114  VSS(58)  GROUND  = GND
  115  DQ(42)  BI  = M_H_DQ<43>
  116  VSS(57)  GROUND  = GND
  117  DQ(52)  BI  = M_H_DQ<53>
  118  VSS(56)  GROUND  = GND
  119  DQ(48)  BI  = M_H_DQ<49>
  120  VSS(55)  GROUND  = GND
  121  DQS15P  BI  = M_H_DQS_DP<15>
  122  DQS15N  BI  = M_H_DQS_DN<15>
  123  VSS(54)  GROUND  = GND
  124  DQ(54)  BI  = M_H_DQ<55>
  125  VSS(53)  GROUND  = GND
  126  DQ(50)  BI  = M_H_DQ<51>
  127  VSS(52)  GROUND  = GND
  128  DQ(60)  BI  = M_H_DQ<61>
  129  VSS(51)  GROUND  = GND
  130  DQ(56)  BI  = M_H_DQ<57>
  131  VSS(50)  GROUND  = GND
  132  DQS16P  BI  = M_H_DQS_DP<16>
  133  DQS16N  BI  = M_H_DQS_DN<16>
  134  VSS(49)  GROUND  = GND
  135  DQ(62)  BI  = M_H_DQ<63>
  136  VSS(48)  GROUND  = GND
  137  DQ(58)  BI  = M_H_DQ<59>
  138  VSS(47)  GROUND  = GND
  139  SA(0)  BI  = GND
  140  SA(1)  BI  = PVPP_GHJ
  141  SCL  BI  = SMB_DDR_GHJ_VPP_SCL
  142  VPP(4)  POWER  = PVPP_GHJ
  143  VPP(3)  POWER  = PVPP_GHJ
  144  RFU(2)  BI  = TP_CH_H_DIMM_H0_RFU_2
  145  \12v\(0)  = P12V_NVDIMM_GHJ
  146  VREFCA  BI  = M_H_VREF
  147  VSS(46)  GROUND  = GND
  148  DQ(5)  BI  = M_H_DQ<4>
  149  VSS(45)  GROUND  = GND
  150  DQ(1)  BI  = M_H_DQ<0>
  151  VSS(44)  GROUND  = GND
  152  DQS0N  BI  = M_H_DQS_DN<0>
  153  DQS0P  BI  = M_H_DQS_DP<0>
  154  VSS(43)  GROUND  = GND
  155  DQ(7)  BI  = M_H_DQ<6>
  156  VSS(42)  GROUND  = GND
  157  DQ(3)  BI  = M_H_DQ<2>
  158  VSS(41)  GROUND  = GND
  159  DQ(13)  BI  = M_H_DQ<12>
  160  VSS(40)  GROUND  = GND
  161  DQ(9)  BI  = M_H_DQ<8>
  162  VSS(39)  GROUND  = GND
  163  DQS1N  BI  = M_H_DQS_DN<1>
  164  DQS1P  BI  = M_H_DQS_DP<1>
  165  VSS(38)  GROUND  = GND
  166  DQ(15)  BI  = M_H_DQ<14>
  167  VSS(37)  GROUND  = GND
  168  DQ(11)  BI  = M_H_DQ<10>
  169  VSS(36)  GROUND  = GND
  170  DQ(21)  BI  = M_H_DQ<20>
  171  VSS(35)  GROUND  = GND
  172  DQ(17)  BI  = M_H_DQ<16>
  173  VSS(34)  GROUND  = GND
  174  DQS2N  BI  = M_H_DQS_DN<2>
  175  DQS2P  BI  = M_H_DQS_DP<2>
  176  VSS(33)  GROUND  = GND
  177  DQ(23)  BI  = M_H_DQ<22>
  178  VSS(32)  GROUND  = GND
  179  DQ(19)  BI  = M_H_DQ<18>
  180  VSS(31)  GROUND  = GND
  181  DQ(29)  BI  = M_H_DQ<28>
  182  VSS(30)  GROUND  = GND
  183  DQ(25)  BI  = M_H_DQ<24>
  184  VSS(29)  GROUND  = GND
  185  DQS3N  BI  = M_H_DQS_DN<3>
  186  DQS3P  BI  = M_H_DQS_DP<3>
  187  VSS(28)  GROUND  = GND
  188  DQ(31)  BI  = M_H_DQ<30>
  189  VSS(27)  GROUND  = GND
  190  DQ(27)  BI  = M_H_DQ<26>
  191  VSS(26)  GROUND  = GND
  192  CB(5)  BI  = M_H_ECC<4>
  193  VSS(25)  GROUND  = GND
  194  CB(1)  BI  = M_H_ECC<0>
  195  VSS(24)  GROUND  = GND
  196  DQS8N  BI  = M_H_DQS_DN<8>
  197  DQS8P  BI  = M_H_DQS_DP<8>
  198  VSS(23)  GROUND  = GND
  199  CB(7)  BI  = M_H_ECC<6>
  200  VSS(22)  GROUND  = GND
  201  CB(3)  BI  = M_H_ECC<2>
  202  VSS(21)  GROUND  = GND
  203  CKE(1)  BI  = M_H_CKE<1>
  204  VDD(12)  POWER  = PVDDQ_GHJ
  205  RFU(0)  BI  = TP_CH_H_DIMM_H0_RFU_0
  206  VDD(11)  POWER  = PVDDQ_GHJ
  207  BG(1)  BI  = M_H_BG<1>
  208  ALERT_N  BI  = M_H_ALERT_N
  209  VDD(10)  POWER  = PVDDQ_GHJ
  210  A11  BI  = M_H_MA<11>
  211  A7  BI  = M_H_MA<7>
  212  VDD(9)  POWER  = PVDDQ_GHJ
  213  A5  BI  = M_H_MA<5>
  214  A4  BI  = M_H_MA<4>
  215  VDD(8)  POWER  = PVDDQ_GHJ
  216  A2  BI  = M_H_MA<2>
  217  VDD(7)  POWER  = PVDDQ_GHJ
  218  CK1P  BI  = M_H_CLK_DP<1>
  219  CK1N  BI  = M_H_CLK_DN<1>
  220  VDD(6)  POWER  = PVDDQ_GHJ
  221  VTT(0)  POWER  = PVTT_GHJ
  222  PAR  BI  = M_H_PAR
  223  VDD(5)  POWER  = PVDDQ_GHJ
  224  BA(1)  BI  = M_H_BA<1>
  225  A10  BI  = M_H_MA<10>
  226  VDD(4)  POWER  = PVDDQ_GHJ
  227  RFU(1)  BI  = TP_CH_H_DIMM_H0_RFU_1
  228  A14_WE_N  BI  = M_H_MA<14>
  229  VDD(3)  POWER  = PVDDQ_GHJ
  230  SAVE_N_NC  BI  = FM_ADR_COMPLETE_GHJ_N
  231  VDD(2)  POWER  = PVDDQ_GHJ
  232  A13  BI  = M_H_MA<13>
  233  VDD(1)  POWER  = PVDDQ_GHJ
  234  A17  BI  = M_H_MA<17>
  235  C(2)  BI  = M_H_C<2>
  236  VDD(0)  POWER  = PVDDQ_GHJ
  237  S3_N_C(1)  BI  = M_H_CS_N<3>
  238  SA(2)  BI  = GND
  239  VSS(20)  GROUND  = GND
  240  DQ(37)  BI  = M_H_DQ<36>
  241  VSS(19)  GROUND  = GND
  242  DQ(33)  BI  = M_H_DQ<32>
  243  VSS(18)  GROUND  = GND
  244  DQS4N  BI  = M_H_DQS_DN<4>
  245  DQS4P  BI  = M_H_DQS_DP<4>
  246  VSS(17)  GROUND  = GND
  247  DQ(39)  BI  = M_H_DQ<38>
  248  VSS(16)  GROUND  = GND
  249  DQ(35)  BI  = M_H_DQ<34>
  250  VSS(15)  GROUND  = GND
  251  DQ(45)  BI  = M_H_DQ<44>
  252  VSS(14)  GROUND  = GND
  253  DQ(41)  BI  = M_H_DQ<40>
  254  VSS(13)  GROUND  = GND
  255  DQS5N  BI  = M_H_DQS_DN<5>
  256  DQS5P  BI  = M_H_DQS_DP<5>
  257  VSS(12)  GROUND  = GND
  258  DQ(47)  BI  = M_H_DQ<46>
  259  VSS(11)  GROUND  = GND
  260  DQ(43)  BI  = M_H_DQ<42>
  261  VSS(10)  GROUND  = GND
  262  DQ(53)  BI  = M_H_DQ<52>
  263  VSS(9)  GROUND  = GND
  264  DQ(49)  BI  = M_H_DQ<48>
  265  VSS(8)  GROUND  = GND
  266  DQS6N  BI  = M_H_DQS_DN<6>
  267  DQS6P  BI  = M_H_DQS_DP<6>
  268  VSS(7)  GROUND  = GND
  269  DQ(55)  BI  = M_H_DQ<54>
  270  VSS(6)  GROUND  = GND
  271  DQ(51)  BI  = M_H_DQ<50>
  272  VSS(5)  GROUND  = GND
  273  DQ(61)  BI  = M_H_DQ<60>
  274  VSS(4)  GROUND  = GND
  275  DQ(57)  BI  = M_H_DQ<56>
  276  VSS(3)  GROUND  = GND
  277  DQS7N  BI  = M_H_DQS_DN<7>
  278  DQS7P  BI  = M_H_DQS_DP<7>
  279  VSS(2)  GROUND  = GND
  280  DQ(63)  BI  = M_H_DQ<62>
  281  VSS(1)  GROUND  = GND
  282  DQ(59)  BI  = M_H_DQ<58>
  283  VSS(0)  GROUND  = GND
  284  VDDSPD  BI  = PVPP_GHJ
  285  SDA  BI  = SMB_DDR_GHJ_VPP_SDA
  286  VPP(1)  POWER  = PVPP_GHJ
  287  VPP(0)  POWER  = PVPP_GHJ
  288  VPP(2)  POWER  = PVPP_GHJ
